# T6G (Grand Teton) — schematic netlist excerpt (pin names and nets, part order shuffled) for the footprints in the layout excerpt that follows; sources: Cadence DE-HDL packaged netlist, KiCad conversion of 04192023_DAF0TMB3IC0_F0TG_MB_C_brd_V02_OCP.brd

R2841  Q_RES  4.7K 5% CHIP  pkg 0402LF  page 127 : A = P3V3_AUX ; B = FM_SWB_PWRGD_N
C248  Q_CAP  1000PF 50V 5% EMPTY  pkg 0402  page 210 : A = PWRGD_PVDDCR_CPU0_P1_R ; B = GND

(kicad_pcb
	(version 20260206)
	(generator "pcbnew")
	(generator_version "10.0")
	(general
		(thickness 1.6)
		(legacy_teardrops no)
	)
	(paper "A4")
	(title_block
		(title "04192023_DAF0TMB3IC0_F0TG_MB_C_brd_V02_OCP.brd")
		(comment 1 "Grand Teton / footprints 6485-6487 of 8354")
	)
	(layers
		(0 "F.Cu" signal "TOP")
		(4 "In1.Cu" signal "GND")
		(6 "In2.Cu" signal "IN1")
		(8 "In3.Cu" signal "GND1")
		(10 "In4.Cu" signal "IN2")
		(12 "In5.Cu" signal "GND2")
		(14 "In6.Cu" signal "IN3")
		(16 "In7.Cu" signal "GND3")
		(18 "In8.Cu" signal "VCC")
		(20 "In9.Cu" signal "VCC1")
		(22 "In10.Cu" signal "GND4")
		(24 "In11.Cu" signal "IN4")
		(26 "In12.Cu" signal "GND5")
		(28 "In13.Cu" signal "IN5")
		(30 "In14.Cu" signal "GND6")
		(32 "In15.Cu" signal "IN6")
		(34 "In16.Cu" signal "GND7")
		(2 "B.Cu" signal "BOTTOM")
		(9 "F.Adhes" user "F.Adhesive")
		(11 "B.Adhes" user "B.Adhesive")
		(13 "F.Paste" user "Package Geometry/Pastemask Top")
		(15 "B.Paste" user "Package Geometry/Pastemask Bottom")
		(5 "F.SilkS" user "Ref Des/Silkscreen Top")
		(7 "B.SilkS" user "Ref Des/Silkscreen Bottom")
		(1 "F.Mask" user "Board Geometry/Soldermask Top")
		(3 "B.Mask" user "Board Geometry/Soldermask Bottom")
		(17 "Dwgs.User" user "User.Drawings")
		(19 "Cmts.User" user "User.Comments")
		(21 "Eco1.User" user "User.Eco1")
		(23 "Eco2.User" user "User.Eco2")
		(25 "Edge.Cuts" user "Board Geometry/Outline")
		(27 "Margin" user)
		(31 "F.CrtYd" user "Package Geometry/Place Bound Top")
		(29 "B.CrtYd" user "Package Geometry/Place Bound Bottom")
		(35 "F.Fab" user "Ref Des/Assembly Top")
		(33 "B.Fab" user "Ref Des/Assembly Bottom")
	)
	(footprint ""
		(layer "B.Cu")
		(at 90.209878 -141.83741)
		(property "Reference" "C248"
			(at 0 0 0)
			(layer "B.SilkS")
			(hide yes)
			(effects
				(font
					(size 1.27 1.27)
				)
				(justify mirror)
			)
		)
		(property "Value" ""
			(at 0 0 0)
			(layer "B.Fab")
			(effects
				(font
					(size 1.27 1.27)
				)
				(justify mirror)
			)
		)
		(duplicate_pad_numbers_are_jumpers no)
		(fp_line
			(start -0.7874 -0.4064)
			(end -0.7874 0.4064)
			(stroke
				(width 0.1524)
				(type default)
			)
			(layer "B.SilkS")
		)
		(fp_line
			(start -0.7874 0.4064)
			(end 0.7874 0.4064)
			(stroke
				(width 0.1524)
				(type default)
			)
			(layer "B.SilkS")
		)
		(fp_line
			(start 0.7874 -0.4064)
			(end -0.7874 -0.4064)
			(stroke
				(width 0.1524)
				(type default)
			)
			(layer "B.SilkS")
		)
		(fp_line
			(start 0.7874 0.4064)
			(end 0.7874 -0.4064)
			(stroke
				(width 0.1524)
				(type default)
			)
			(layer "B.SilkS")
		)
		(fp_line
			(start -0.67945 -0.3048)
			(end -0.67945 0.3048)
			(stroke
				(width 0.1)
				(type default)
			)
			(layer "B.Fab")
		)
		(fp_line
			(start -0.67945 0.3048)
			(end -0.120396 0.3048)
			(stroke
				(width 0.1)
				(type default)
			)
			(layer "B.Fab")
		)
		(fp_line
			(start -0.12065 -0.3048)
			(end -0.67945 -0.3048)
			(stroke
				(width 0.1)
				(type default)
			)
			(layer "B.Fab")
		)
		(fp_line
			(start -0.12065 -0.2794)
			(end -0.12065 -0.3048)
			(stroke
				(width 0.1)
				(type default)
			)
			(layer "B.Fab")
		)
		(fp_line
			(start -0.120396 0.2794)
			(end 0.12065 0.2794)
			(stroke
				(width 0.1)
				(type default)
			)
			(layer "B.Fab")
		)
		(fp_line
			(start -0.120396 0.3048)
			(end -0.120396 0.2794)
			(stroke
				(width 0.1)
				(type default)
			)
			(layer "B.Fab")
		)
		(fp_line
			(start 0.12065 -0.305054)
			(end 0.12065 -0.2794)
			(stroke
				(width 0.1)
				(type default)
			)
			(layer "B.Fab")
		)
		(fp_line
			(start 0.12065 -0.2794)
			(end -0.12065 -0.2794)
			(stroke
				(width 0.1)
				(type default)
			)
			(layer "B.Fab")
		)
		(fp_line
			(start 0.12065 0.2794)
			(end 0.12065 0.3048)
			(stroke
				(width 0.1)
				(type default)
			)
			(layer "B.Fab")
		)
		(fp_line
			(start 0.12065 0.3048)
			(end 0.67945 0.3048)
			(stroke
				(width 0.1)
				(type default)
			)
			(layer "B.Fab")
		)
		(fp_line
			(start 0.67945 -0.305054)
			(end 0.12065 -0.305054)
			(stroke
				(width 0.1)
				(type default)
			)
			(layer "B.Fab")
		)
		(fp_line
			(start 0.67945 0.3048)
			(end 0.67945 -0.305054)
			(stroke
				(width 0.1)
				(type default)
			)
			(layer "B.Fab")
		)
		(pad "1" smd circle
			(at 0.40005 0 180)
			(size 0 0)
			(layers "B.Cu" "B.Mask" "B.Paste")
			(net "PWRGD_PVDDCR_CPU0_P1_R")
		)
		(pad "2" smd circle
			(at -0.40005 0 180)
			(size 0 0)
			(layers "B.Cu" "B.Mask" "B.Paste")
			(net "GND")
		)
	)
	(footprint ""
		(layer "B.Cu")
		(at 5.985002 -403.945852 180)
		(property "Reference" ""
			(at 0 0 0)
			(layer "B.SilkS")
			(hide yes)
			(effects
				(font
					(size 1.27 1.27)
				)
				(justify mirror)
			)
		)
		(property "Value" ""
			(at 0 0 0)
			(layer "B.Fab")
			(effects
				(font
					(size 1.27 1.27)
				)
				(justify mirror)
			)
		)
		(duplicate_pad_numbers_are_jumpers no)
		(pad "1" smd circle
			(at 0 0)
			(size 0.9906 0.9906)
			(layers "B.Cu" "B.Mask" "B.Paste")
			(net "Net_2231")
		)
		(zone
			(layer "B.Cu")
			(hatch none 0.5)
			(connect_pads
				(clearance 0)
			)
			(min_thickness 0.25)
			(keepout
				(tracks not_allowed)
				(vias allowed)
				(pads allowed)
				(copperpour not_allowed)
				(footprints allowed)
			)
			(placement
				(enabled no)
				(sheetname "")
			)
			(fill
				(thermal_gap 0.5)
				(thermal_bridge_width 0.5)
				(island_removal_mode 0)
			)
			(polygon
				(pts
					(arc
						(start 7.610602 -403.945852)
						(mid 4.359402 -403.945852)
						(end 7.610602 -403.945852)
					)
				)
			)
		)
	)
	(footprint ""
		(layer "B.Cu")
		(at 354.812854 -420.626032 90)
		(property "Reference" "R2841"
			(at 0 0 90)
			(layer "B.SilkS")
			(hide yes)
			(effects
				(font
					(size 1.27 1.27)
				)
				(justify mirror)
			)
		)
		(property "Value" ""
			(at 0 0 90)
			(layer "B.Fab")
			(effects
				(font
					(size 1.27 1.27)
				)
				(justify mirror)
			)
		)
		(duplicate_pad_numbers_are_jumpers no)
		(fp_line
			(start 0.7874 -0.4064)
			(end -0.7874 -0.4064)
			(stroke
				(width 0.1524)
				(type default)
			)
			(layer "B.SilkS")
		)
		(fp_line
			(start -0.7874 -0.4064)
			(end -0.7874 0.4064)
			(stroke
				(width 0.1524)
				(type default)
			)
			(layer "B.SilkS")
		)
		(fp_line
			(start 0.7874 0.4064)
			(end 0.7874 -0.4064)
			(stroke
				(width 0.1524)
				(type default)
			)
			(layer "B.SilkS")
		)
		(fp_line
			(start -0.7874 0.4064)
			(end 0.7874 0.4064)
			(stroke
				(width 0.1524)
				(type default)
			)
			(layer "B.SilkS")
		)
		(fp_line
			(start 0.67945 -0.305054)
			(end 0.12065 -0.305054)
			(stroke
				(width 0.1)
				(type default)
			)
			(layer "B.Fab")
		)
		(fp_line
			(start 0.12065 -0.305054)
			(end 0.12065 -0.2794)
			(stroke
				(width 0.1)
				(type default)
			)
			(layer "B.Fab")
		)
		(fp_line
			(start -0.12065 -0.3048)
			(end -0.67945 -0.3048)
			(stroke
				(width 0.1)
				(type default)
			)
			(layer "B.Fab")
		)
		(fp_line
			(start -0.67945 -0.3048)
			(end -0.67945 0.3048)
			(stroke
				(width 0.1)
				(type default)
			)
			(layer "B.Fab")
		)
		(fp_line
			(start 0.12065 -0.2794)
			(end -0.12065 -0.2794)
			(stroke
				(width 0.1)
				(type default)
			)
			(layer "B.Fab")
		)
		(fp_line
			(start -0.12065 -0.2794)
			(end -0.12065 -0.3048)
			(stroke
				(width 0.1)
				(type default)
			)
			(layer "B.Fab")
		)
		(fp_line
			(start 0.12065 0.2794)
			(end 0.12065 0.3048)
			(stroke
				(width 0.1)
				(type default)
			)
			(layer "B.Fab")
		)
		(fp_line
			(start -0.120396 0.2794)
			(end 0.12065 0.2794)
			(stroke
				(width 0.1)
				(type default)
			)
			(layer "B.Fab")
		)
		(fp_line
			(start 0.67945 0.3048)
			(end 0.67945 -0.305054)
			(stroke
				(width 0.1)
				(type default)
			)
			(layer "B.Fab")
		)
		(fp_line
			(start 0.12065 0.3048)
			(end 0.67945 0.3048)
			(stroke
				(width 0.1)
				(type default)
			)
			(layer "B.Fab")
		)
		(fp_line
			(start -0.120396 0.3048)
			(end -0.120396 0.2794)
			(stroke
				(width 0.1)
				(type default)
			)
			(layer "B.Fab")
		)
		(fp_line
			(start -0.67945 0.3048)
			(end -0.120396 0.3048)
			(stroke
				(width 0.1)
				(type default)
			)
			(layer "B.Fab")
		)
		(pad "1" smd circle
			(at 0.40005 0 270)
			(size 0 0)
			(layers "B.Cu" "B.Mask" "B.Paste")
			(net "P3V3_AUX")
		)
		(pad "2" smd circle
			(at -0.40005 0 270)
			(size 0 0)
			(layers "B.Cu" "B.Mask" "B.Paste")
			(net "FM_SWB_PWRGD_N")
		)
	)
)
